# S9S_MB_2U (Grand Teton) — schematic netlist excerpt (pin names and nets, part order shuffled) for the footprints in the layout excerpt that follows; sources: Cadence DE-HDL packaged netlist, KiCad conversion of 03242023_DA0F0TMBIJ0_F0T_Motherboard_J_brd_V01_OCP.brd

U64  M24128BWMN6TP  M24128-BWMN6TP IC  pkg SOIC8XH  page 243
  E0  = MB_FRU_ADDR0
  E1  = MB_FRU_ADDR1
  E2  = MB_FRU_ADDR2
  VSS  = GND
  SDA  = SMB_FRU_3V3AUX_SDA
  SCL  = SMB_FRU_3V3AUX_SCL
  \wc#\  = PD_MB_FRU_WP
  VCC  = P3V3_AUX

PC1846  Q_CAP  1UF 16V 10% X6S  pkg C0402  page 258 : A = SW_P5V_AUX_FLT ; B = GND

(kicad_pcb
	(version 20260206)
	(generator "pcbnew")
	(generator_version "10.0")
	(general
		(thickness 1.6)
		(legacy_teardrops no)
	)
	(paper "A4")
	(title_block
		(title "03242023_DA0F0TMBIJ0_F0T_Motherboard_J_brd_V01_OCP.brd")
		(comment 1 "Grand Teton / footprints 2674-2676 of 6105")
	)
	(layers
		(0 "F.Cu" signal "TOP")
		(4 "In1.Cu" signal "GND")
		(6 "In2.Cu" signal "IN1")
		(8 "In3.Cu" signal "GND1")
		(10 "In4.Cu" signal "IN2")
		(12 "In5.Cu" signal "GND2")
		(14 "In6.Cu" signal "IN3")
		(16 "In7.Cu" signal "GND3")
		(18 "In8.Cu" signal "VCC")
		(20 "In9.Cu" signal "VCC1")
		(22 "In10.Cu" signal "GND4")
		(24 "In11.Cu" signal "IN4")
		(26 "In12.Cu" signal "GND5")
		(28 "In13.Cu" signal "IN5")
		(30 "In14.Cu" signal "GND6")
		(32 "In15.Cu" signal "IN6")
		(34 "In16.Cu" signal "GND7")
		(2 "B.Cu" signal "BOTTOM")
		(9 "F.Adhes" user "F.Adhesive")
		(11 "B.Adhes" user "B.Adhesive")
		(13 "F.Paste" user "Package Geometry/Pastemask Top")
		(15 "B.Paste" user "Package Geometry/Pastemask Bottom")
		(5 "F.SilkS" user "Ref Des/Silkscreen Top")
		(7 "B.SilkS" user "Ref Des/Silkscreen Bottom")
		(1 "F.Mask" user "Board Geometry/Soldermask Top")
		(3 "B.Mask" user "Board Geometry/Soldermask Bottom")
		(17 "Dwgs.User" user "User.Drawings")
		(19 "Cmts.User" user "User.Comments")
		(21 "Eco1.User" user "User.Eco1")
		(23 "Eco2.User" user "User.Eco2")
		(25 "Edge.Cuts" user "Board Geometry/Outline")
		(27 "Margin" user)
		(31 "F.CrtYd" user "Package Geometry/Place Bound Top")
		(29 "B.CrtYd" user "Package Geometry/Place Bound Bottom")
		(35 "F.Fab" user "Ref Des/Assembly Top")
		(33 "B.Fab" user "Ref Des/Assembly Bottom")
	)
	(footprint ""
		(layer "F.Cu")
		(at 284.39491 -94.42069)
		(property "Reference" "U64"
			(at -1.4986 -3.597148 0)
			(unlocked yes)
			(layer "F.SilkS")
			(effects
				(font
					(size 0.7874 0.5842)
					(thickness 0.1524)
				)
				(justify left)
			)
		)
		(property "Value" ""
			(at 0 0 0)
			(layer "F.Fab")
			(effects
				(font
					(size 1.27 1.27)
				)
			)
		)
		(duplicate_pad_numbers_are_jumpers no)
		(fp_line
			(start -1.8288 -2.500122)
			(end -1.8288 2.500122)
			(stroke
				(width 0.1524)
				(type default)
			)
			(layer "F.SilkS")
		)
		(fp_line
			(start -1.8288 2.500122)
			(end 1.8288 2.500122)
			(stroke
				(width 0.1524)
				(type default)
			)
			(layer "F.SilkS")
		)
		(fp_line
			(start -1.077722 -2.500122)
			(end -1.8288 -2.500122)
			(stroke
				(width 0.1524)
				(type default)
			)
			(layer "F.SilkS")
		)
		(fp_line
			(start 0 -1.4224)
			(end -1.077722 -2.500122)
			(stroke
				(width 0.1524)
				(type default)
			)
			(layer "F.SilkS")
		)
		(fp_line
			(start 1.077722 -2.500122)
			(end 0 -1.4224)
			(stroke
				(width 0.1524)
				(type default)
			)
			(layer "F.SilkS")
		)
		(fp_line
			(start 1.8288 -2.500122)
			(end 1.077722 -2.500122)
			(stroke
				(width 0.1524)
				(type default)
			)
			(layer "F.SilkS")
		)
		(fp_line
			(start 1.8288 2.500122)
			(end 1.8288 -2.500122)
			(stroke
				(width 0.1524)
				(type default)
			)
			(layer "F.SilkS")
		)
		(fp_poly
			(pts
				(xy -2.291588 -3.983228) (xy -2.799588 -2.967228) (xy -3.307588 -3.983228)
			)
			(stroke
				(width 0)
				(type default)
			)
			(fill yes)
			(layer "F.SilkS")
		)
		(fp_line
			(start -1.999996 -2.500122)
			(end -1.999996 2.500122)
			(stroke
				(width 0.1)
				(type default)
			)
			(layer "F.Fab")
		)
		(fp_line
			(start -1.999996 2.500122)
			(end 1.999996 2.500122)
			(stroke
				(width 0.1)
				(type default)
			)
			(layer "F.Fab")
		)
		(fp_line
			(start 1.999996 -2.500122)
			(end -1.999996 -2.500122)
			(stroke
				(width 0.1)
				(type default)
			)
			(layer "F.Fab")
		)
		(fp_line
			(start 1.999996 2.500122)
			(end 1.999996 -2.500122)
			(stroke
				(width 0.1)
				(type default)
			)
			(layer "F.Fab")
		)
		(fp_poly
			(pts
				(xy -4.5085 -2.413) (xy -4.5085 -1.397) (xy -3.4925 -1.905)
			)
			(stroke
				(width 0)
				(type default)
			)
			(fill yes)
			(layer "F.Fab")
		)
		(pad "1" smd rect
			(at -2.599944 -1.905 270)
			(size 0.889 1.27)
			(layers "F.Cu" "F.Mask" "F.Paste")
			(net "MB_FRU_ADDR0")
		)
		(pad "2" smd rect
			(at -2.599944 -0.635 270)
			(size 0.889 1.27)
			(layers "F.Cu" "F.Mask" "F.Paste")
			(net "MB_FRU_ADDR1")
		)
		(pad "3" smd rect
			(at -2.599944 0.635 270)
			(size 0.889 1.27)
			(layers "F.Cu" "F.Mask" "F.Paste")
			(net "MB_FRU_ADDR2")
		)
		(pad "4" smd rect
			(at -2.599944 1.905 270)
			(size 0.889 1.27)
			(layers "F.Cu" "F.Mask" "F.Paste")
			(net "GND")
		)
		(pad "5" smd rect
			(at 2.599944 1.905 270)
			(size 0.889 1.27)
			(layers "F.Cu" "F.Mask" "F.Paste")
			(net "SMB_FRU_3V3AUX_SDA")
		)
		(pad "6" smd rect
			(at 2.599944 0.635 270)
			(size 0.889 1.27)
			(layers "F.Cu" "F.Mask" "F.Paste")
			(net "SMB_FRU_3V3AUX_SCL")
		)
		(pad "7" smd rect
			(at 2.599944 -0.635 270)
			(size 0.889 1.27)
			(layers "F.Cu" "F.Mask" "F.Paste")
			(net "PD_MB_FRU_WP")
		)
		(pad "8" smd rect
			(at 2.599944 -1.905 270)
			(size 0.889 1.27)
			(layers "F.Cu" "F.Mask" "F.Paste")
			(net "P3V3_AUX")
		)
	)
	(footprint ""
		(layer "F.Cu")
		(at 6.43128 -37.252148)
		(property "Reference" ""
			(at 0 0 0)
			(layer "F.SilkS")
			(hide yes)
			(effects
				(font
					(size 1.27 1.27)
				)
			)
		)
		(property "Value" ""
			(at 0 0 0)
			(layer "F.Fab")
			(effects
				(font
					(size 1.27 1.27)
				)
			)
		)
		(duplicate_pad_numbers_are_jumpers no)
		(pad "1" smd circle
			(at 0 0)
			(size 0.9906 0.9906)
			(layers "F.Cu" "F.Mask" "F.Paste")
			(net "Net_8482")
		)
		(zone
			(layer "F.Cu")
			(hatch none 0.5)
			(connect_pads
				(clearance 0)
			)
			(min_thickness 0.25)
			(keepout
				(tracks not_allowed)
				(vias allowed)
				(pads allowed)
				(copperpour not_allowed)
				(footprints allowed)
			)
			(placement
				(enabled no)
				(sheetname "")
			)
			(fill
				(thermal_gap 0.5)
				(thermal_bridge_width 0.5)
				(island_removal_mode 0)
			)
			(polygon
				(pts
					(arc
						(start 8.05688 -37.252148)
						(mid 4.80568 -37.252148)
						(end 8.05688 -37.252148)
					)
				)
			)
		)
	)
	(footprint ""
		(layer "F.Cu")
		(at 454.662794 -384.301492 -90)
		(property "Reference" "PC1846"
			(at 0 0 270)
			(layer "F.SilkS")
			(hide yes)
			(effects
				(font
					(size 1.27 1.27)
				)
			)
		)
		(property "Value" ""
			(at 0 0 270)
			(layer "F.Fab")
			(effects
				(font
					(size 1.27 1.27)
				)
			)
		)
		(duplicate_pad_numbers_are_jumpers no)
		(fp_line
			(start -0.7874 0.4064)
			(end -0.7874 -0.4064)
			(stroke
				(width 0.1524)
				(type default)
			)
			(layer "F.SilkS")
		)
		(fp_line
			(start 0.7874 0.4064)
			(end -0.7874 0.4064)
			(stroke
				(width 0.1524)
				(type default)
			)
			(layer "F.SilkS")
		)
		(fp_line
			(start -0.7874 -0.4064)
			(end 0.7874 -0.4064)
			(stroke
				(width 0.1524)
				(type default)
			)
			(layer "F.SilkS")
		)
		(fp_line
			(start 0.7874 -0.4064)
			(end 0.7874 0.4064)
			(stroke
				(width 0.1524)
				(type default)
			)
			(layer "F.SilkS")
		)
		(fp_line
			(start -0.67945 0.3048)
			(end -0.67945 -0.305054)
			(stroke
				(width 0.1)
				(type default)
			)
			(layer "F.Fab")
		)
		(fp_line
			(start -0.12065 0.3048)
			(end -0.67945 0.3048)
			(stroke
				(width 0.1)
				(type default)
			)
			(layer "F.Fab")
		)
		(fp_line
			(start 0.120396 0.3048)
			(end 0.120396 0.2794)
			(stroke
				(width 0.1)
				(type default)
			)
			(layer "F.Fab")
		)
		(fp_line
			(start 0.67945 0.3048)
			(end 0.120396 0.3048)
			(stroke
				(width 0.1)
				(type default)
			)
			(layer "F.Fab")
		)
		(fp_line
			(start -0.12065 0.2794)
			(end -0.12065 0.3048)
			(stroke
				(width 0.1)
				(type default)
			)
			(layer "F.Fab")
		)
		(fp_line
			(start 0.120396 0.2794)
			(end -0.12065 0.2794)
			(stroke
				(width 0.1)
				(type default)
			)
			(layer "F.Fab")
		)
		(fp_line
			(start -0.12065 -0.2794)
			(end 0.12065 -0.2794)
			(stroke
				(width 0.1)
				(type default)
			)
			(layer "F.Fab")
		)
		(fp_line
			(start 0.12065 -0.2794)
			(end 0.12065 -0.3048)
			(stroke
				(width 0.1)
				(type default)
			)
			(layer "F.Fab")
		)
		(fp_line
			(start 0.12065 -0.3048)
			(end 0.67945 -0.3048)
			(stroke
				(width 0.1)
				(type default)
			)
			(layer "F.Fab")
		)
		(fp_line
			(start 0.67945 -0.3048)
			(end 0.67945 0.3048)
			(stroke
				(width 0.1)
				(type default)
			)
			(layer "F.Fab")
		)
		(fp_line
			(start -0.67945 -0.305054)
			(end -0.12065 -0.305054)
			(stroke
				(width 0.1)
				(type default)
			)
			(layer "F.Fab")
		)
		(fp_line
			(start -0.12065 -0.305054)
			(end -0.12065 -0.2794)
			(stroke
				(width 0.1)
				(type default)
			)
			(layer "F.Fab")
		)
		(pad "1" smd circle
			(at -0.40005 0 270)
			(size 0 0)
			(layers "F.Cu" "F.Mask" "F.Paste")
			(net "SW_P5V_AUX_FLT")
		)
		(pad "2" smd circle
			(at 0.40005 0 270)
			(size 0 0)
			(layers "F.Cu" "F.Mask" "F.Paste")
			(net "GND")
		)
	)
)
